(kicad_pcb
	(version 20260206)
	(generator "pcbnew")
	(generator_version "10.0")
	(general
		(thickness 1.6)
		(legacy_teardrops no)
	)
	(paper "A4")
	(title_block
		(title "01162023_DA0F0TEBIF0_F0T_Expander_BD_F_brd_V02_OCP.brd")
		(comment 1 "Grand Teton / footprints 3276-3281 of 9728")
	)
	(layers
		(0 "F.Cu" signal "TOP")
		(4 "In1.Cu" signal "GND")
		(6 "In2.Cu" signal "VCC")
		(8 "In3.Cu" signal "VCC1")
		(10 "In4.Cu" signal "GND1")
		(12 "In5.Cu" signal "IN1")
		(14 "In6.Cu" signal "GND2")
		(16 "In7.Cu" signal "IN2")
		(18 "In8.Cu" signal "GND3")
		(20 "In9.Cu" signal "IN3")
		(22 "In10.Cu" signal "GND4")
		(24 "In11.Cu" signal "IN4")
		(26 "In12.Cu" signal "GND5")
		(28 "In13.Cu" signal "IN5")
		(30 "In14.Cu" signal "GND6")
		(32 "In15.Cu" signal "IN6")
		(34 "In16.Cu" signal "GND7")
		(2 "B.Cu" signal "BOTTOM")
		(9 "F.Adhes" user "F.Adhesive")
		(11 "B.Adhes" user "B.Adhesive")
		(13 "F.Paste" user "Package Geometry/Pastemask Top")
		(15 "B.Paste" user "Package Geometry/Pastemask Bottom")
		(5 "F.SilkS" user "Ref Des/Silkscreen Top")
		(7 "B.SilkS" user "Ref Des/Silkscreen Bottom")
		(1 "F.Mask" user "Board Geometry/Soldermask Top")
		(3 "B.Mask" user "Board Geometry/Soldermask Bottom")
		(17 "Dwgs.User" user "User.Drawings")
		(19 "Cmts.User" user "User.Comments")
		(21 "Eco1.User" user "User.Eco1")
		(23 "Eco2.User" user "User.Eco2")
		(25 "Edge.Cuts" user "Board Geometry/Outline")
		(27 "Margin" user)
		(31 "F.CrtYd" user "Package Geometry/Place Bound Top")
		(29 "B.CrtYd" user "Package Geometry/Place Bound Bottom")
		(35 "F.Fab" user "Ref Des/Assembly Top")
		(33 "B.Fab" user "Ref Des/Assembly Bottom")
	)
	(footprint ""
		(layer "F.Cu")
		(at 308.681882 -37.025072)
		(property "Reference" "R5689"
			(at 0 0 0)
			(layer "F.SilkS")
			(hide yes)
			(effects
				(font
					(size 1.27 1.27)
				)
			)
		)
		(property "Value" ""
			(at 0 0 0)
			(layer "F.Fab")
			(effects
				(font
					(size 1.27 1.27)
				)
			)
		)
		(duplicate_pad_numbers_are_jumpers no)
		(fp_line
			(start -0.7874 -0.4064)
			(end 0.7874 -0.4064)
			(stroke
				(width 0.1524)
				(type default)
			)
			(layer "F.SilkS")
		)
		(fp_line
			(start -0.7874 0.4064)
			(end -0.7874 -0.4064)
			(stroke
				(width 0.1524)
				(type default)
			)
			(layer "F.SilkS")
		)
		(fp_line
			(start 0.7874 -0.4064)
			(end 0.7874 0.4064)
			(stroke
				(width 0.1524)
				(type default)
			)
			(layer "F.SilkS")
		)
		(fp_line
			(start 0.7874 0.4064)
			(end -0.7874 0.4064)
			(stroke
				(width 0.1524)
				(type default)
			)
			(layer "F.SilkS")
		)
		(fp_line
			(start -0.67945 -0.305054)
			(end -0.12065 -0.305054)
			(stroke
				(width 0.1)
				(type default)
			)
			(layer "F.Fab")
		)
		(fp_line
			(start -0.67945 0.3048)
			(end -0.67945 -0.305054)
			(stroke
				(width 0.1)
				(type default)
			)
			(layer "F.Fab")
		)
		(fp_line
			(start -0.12065 -0.305054)
			(end -0.12065 -0.2794)
			(stroke
				(width 0.1)
				(type default)
			)
			(layer "F.Fab")
		)
		(fp_line
			(start -0.12065 -0.2794)
			(end 0.12065 -0.2794)
			(stroke
				(width 0.1)
				(type default)
			)
			(layer "F.Fab")
		)
		(fp_line
			(start -0.12065 0.2794)
			(end -0.12065 0.3048)
			(stroke
				(width 0.1)
				(type default)
			)
			(layer "F.Fab")
		)
		(fp_line
			(start -0.12065 0.3048)
			(end -0.67945 0.3048)
			(stroke
				(width 0.1)
				(type default)
			)
			(layer "F.Fab")
		)
		(fp_line
			(start 0.120396 0.2794)
			(end -0.12065 0.2794)
			(stroke
				(width 0.1)
				(type default)
			)
			(layer "F.Fab")
		)
		(fp_line
			(start 0.120396 0.3048)
			(end 0.120396 0.2794)
			(stroke
				(width 0.1)
				(type default)
			)
			(layer "F.Fab")
		)
		(fp_line
			(start 0.12065 -0.3048)
			(end 0.67945 -0.3048)
			(stroke
				(width 0.1)
				(type default)
			)
			(layer "F.Fab")
		)
		(fp_line
			(start 0.12065 -0.2794)
			(end 0.12065 -0.3048)
			(stroke
				(width 0.1)
				(type default)
			)
			(layer "F.Fab")
		)
		(fp_line
			(start 0.67945 -0.3048)
			(end 0.67945 0.3048)
			(stroke
				(width 0.1)
				(type default)
			)
			(layer "F.Fab")
		)
		(fp_line
			(start 0.67945 0.3048)
			(end 0.120396 0.3048)
			(stroke
				(width 0.1)
				(type default)
			)
			(layer "F.Fab")
		)
		(pad "1" smd circle
			(at -0.40005 0)
			(size 0 0)
			(layers "F.Cu" "F.Mask" "F.Paste")
			(net "RST_SMB_SSD_R_N")
		)
		(pad "2" smd circle
			(at 0.40005 0)
			(size 0 0)
			(layers "F.Cu" "F.Mask" "F.Paste")
			(net "RST_SMB_SSD11_N")
		)
	)
	(footprint ""
		(layer "F.Cu")
		(at 460.611982 -114.960654)
		(property "Reference" "PR7062"
			(at 0 0 0)
			(layer "F.SilkS")
			(hide yes)
			(effects
				(font
					(size 1.27 1.27)
				)
			)
		)
		(property "Value" ""
			(at 0 0 0)
			(layer "F.Fab")
			(effects
				(font
					(size 1.27 1.27)
				)
			)
		)
		(duplicate_pad_numbers_are_jumpers no)
		(fp_line
			(start -0.7874 -0.4064)
			(end 0.7874 -0.4064)
			(stroke
				(width 0.1524)
				(type default)
			)
			(layer "F.SilkS")
		)
		(fp_line
			(start -0.7874 0.4064)
			(end -0.7874 -0.4064)
			(stroke
				(width 0.1524)
				(type default)
			)
			(layer "F.SilkS")
		)
		(fp_line
			(start 0.7874 -0.4064)
			(end 0.7874 0.4064)
			(stroke
				(width 0.1524)
				(type default)
			)
			(layer "F.SilkS")
		)
		(fp_line
			(start 0.7874 0.4064)
			(end -0.7874 0.4064)
			(stroke
				(width 0.1524)
				(type default)
			)
			(layer "F.SilkS")
		)
		(fp_line
			(start -0.67945 -0.305054)
			(end -0.12065 -0.305054)
			(stroke
				(width 0.1)
				(type default)
			)
			(layer "F.Fab")
		)
		(fp_line
			(start -0.67945 0.3048)
			(end -0.67945 -0.305054)
			(stroke
				(width 0.1)
				(type default)
			)
			(layer "F.Fab")
		)
		(fp_line
			(start -0.12065 -0.305054)
			(end -0.12065 -0.2794)
			(stroke
				(width 0.1)
				(type default)
			)
			(layer "F.Fab")
		)
		(fp_line
			(start -0.12065 -0.2794)
			(end 0.12065 -0.2794)
			(stroke
				(width 0.1)
				(type default)
			)
			(layer "F.Fab")
		)
		(fp_line
			(start -0.12065 0.2794)
			(end -0.12065 0.3048)
			(stroke
				(width 0.1)
				(type default)
			)
			(layer "F.Fab")
		)
		(fp_line
			(start -0.12065 0.3048)
			(end -0.67945 0.3048)
			(stroke
				(width 0.1)
				(type default)
			)
			(layer "F.Fab")
		)
		(fp_line
			(start 0.120396 0.2794)
			(end -0.12065 0.2794)
			(stroke
				(width 0.1)
				(type default)
			)
			(layer "F.Fab")
		)
		(fp_line
			(start 0.120396 0.3048)
			(end 0.120396 0.2794)
			(stroke
				(width 0.1)
				(type default)
			)
			(layer "F.Fab")
		)
		(fp_line
			(start 0.12065 -0.3048)
			(end 0.67945 -0.3048)
			(stroke
				(width 0.1)
				(type default)
			)
			(layer "F.Fab")
		)
		(fp_line
			(start 0.12065 -0.2794)
			(end 0.12065 -0.3048)
			(stroke
				(width 0.1)
				(type default)
			)
			(layer "F.Fab")
		)
		(fp_line
			(start 0.67945 -0.3048)
			(end 0.67945 0.3048)
			(stroke
				(width 0.1)
				(type default)
			)
			(layer "F.Fab")
		)
		(fp_line
			(start 0.67945 0.3048)
			(end 0.120396 0.3048)
			(stroke
				(width 0.1)
				(type default)
			)
			(layer "F.Fab")
		)
		(pad "1" smd circle
			(at -0.40005 0)
			(size 0 0)
			(layers "F.Cu" "F.Mask" "F.Paste")
			(net "P12V_NIC7_CO_IMON_VR")
		)
		(pad "2" smd circle
			(at 0.40005 0)
			(size 0 0)
			(layers "F.Cu" "F.Mask" "F.Paste")
			(net "GND")
		)
	)
	(footprint ""
		(layer "F.Cu")
		(at 212.822536 -44.341542 90)
		(property "Reference" "R591"
			(at 0 0 90)
			(layer "F.SilkS")
			(hide yes)
			(effects
				(font
					(size 1.27 1.27)
				)
			)
		)
		(property "Value" ""
			(at 0 0 90)
			(layer "F.Fab")
			(effects
				(font
					(size 1.27 1.27)
				)
			)
		)
		(duplicate_pad_numbers_are_jumpers no)
		(fp_line
			(start 0.7874 -0.4064)
			(end 0.7874 0.4064)
			(stroke
				(width 0.1524)
				(type default)
			)
			(layer "F.SilkS")
		)
		(fp_line
			(start -0.7874 -0.4064)
			(end 0.7874 -0.4064)
			(stroke
				(width 0.1524)
				(type default)
			)
			(layer "F.SilkS")
		)
		(fp_line
			(start 0.7874 0.4064)
			(end -0.7874 0.4064)
			(stroke
				(width 0.1524)
				(type default)
			)
			(layer "F.SilkS")
		)
		(fp_line
			(start -0.7874 0.4064)
			(end -0.7874 -0.4064)
			(stroke
				(width 0.1524)
				(type default)
			)
			(layer "F.SilkS")
		)
		(fp_line
			(start -0.12065 -0.305054)
			(end -0.12065 -0.2794)
			(stroke
				(width 0.1)
				(type default)
			)
			(layer "F.Fab")
		)
		(fp_line
			(start -0.67945 -0.305054)
			(end -0.12065 -0.305054)
			(stroke
				(width 0.1)
				(type default)
			)
			(layer "F.Fab")
		)
		(fp_line
			(start 0.67945 -0.3048)
			(end 0.67945 0.3048)
			(stroke
				(width 0.1)
				(type default)
			)
			(layer "F.Fab")
		)
		(fp_line
			(start 0.12065 -0.3048)
			(end 0.67945 -0.3048)
			(stroke
				(width 0.1)
				(type default)
			)
			(layer "F.Fab")
		)
		(fp_line
			(start 0.12065 -0.2794)
			(end 0.12065 -0.3048)
			(stroke
				(width 0.1)
				(type default)
			)
			(layer "F.Fab")
		)
		(fp_line
			(start -0.12065 -0.2794)
			(end 0.12065 -0.2794)
			(stroke
				(width 0.1)
				(type default)
			)
			(layer "F.Fab")
		)
		(fp_line
			(start 0.120396 0.2794)
			(end -0.12065 0.2794)
			(stroke
				(width 0.1)
				(type default)
			)
			(layer "F.Fab")
		)
		(fp_line
			(start -0.12065 0.2794)
			(end -0.12065 0.3048)
			(stroke
				(width 0.1)
				(type default)
			)
			(layer "F.Fab")
		)
		(fp_line
			(start 0.67945 0.3048)
			(end 0.120396 0.3048)
			(stroke
				(width 0.1)
				(type default)
			)
			(layer "F.Fab")
		)
		(fp_line
			(start 0.120396 0.3048)
			(end 0.120396 0.2794)
			(stroke
				(width 0.1)
				(type default)
			)
			(layer "F.Fab")
		)
		(fp_line
			(start -0.12065 0.3048)
			(end -0.67945 0.3048)
			(stroke
				(width 0.1)
				(type default)
			)
			(layer "F.Fab")
		)
		(fp_line
			(start -0.67945 0.3048)
			(end -0.67945 -0.305054)
			(stroke
				(width 0.1)
				(type default)
			)
			(layer "F.Fab")
		)
		(pad "1" smd circle
			(at -0.40005 0 90)
			(size 0 0)
			(layers "F.Cu" "F.Mask" "F.Paste")
			(net "P12V_SSD7")
		)
		(pad "2" smd circle
			(at 0.40005 0 90)
			(size 0 0)
			(layers "F.Cu" "F.Mask" "F.Paste")
			(net "P12V_SSD7_VIN_N")
		)
	)
	(footprint ""
		(layer "F.Cu")
		(at 41.987978 -45.704252 90)
		(property "Reference" "R516"
			(at 0 0 90)
			(layer "F.SilkS")
			(hide yes)
			(effects
				(font
					(size 1.27 1.27)
				)
			)
		)
		(property "Value" ""
			(at 0 0 90)
			(layer "F.Fab")
			(effects
				(font
					(size 1.27 1.27)
				)
			)
		)
		(duplicate_pad_numbers_are_jumpers no)
		(fp_line
			(start 3.937508 -1.8796)
			(end -3.937508 -1.8796)
			(stroke
				(width 0.1524)
				(type default)
			)
			(layer "F.SilkS")
		)
		(fp_line
			(start -3.937508 -1.8796)
			(end -3.937508 1.8796)
			(stroke
				(width 0.1524)
				(type default)
			)
			(layer "F.SilkS")
		)
		(fp_line
			(start 3.937508 1.8796)
			(end 3.937508 -1.8796)
			(stroke
				(width 0.1524)
				(type default)
			)
			(layer "F.SilkS")
		)
		(fp_line
			(start -3.937508 1.8796)
			(end 3.937508 1.8796)
			(stroke
				(width 0.1524)
				(type default)
			)
			(layer "F.SilkS")
		)
		(fp_line
			(start 3.275076 -1.674876)
			(end -3.275076 -1.674876)
			(stroke
				(width 0.1)
				(type default)
			)
			(layer "F.Fab")
		)
		(fp_line
			(start -3.275076 -1.674876)
			(end -3.275076 1.674876)
			(stroke
				(width 0.1)
				(type default)
			)
			(layer "F.Fab")
		)
		(fp_line
			(start 3.275076 1.674876)
			(end 3.275076 -1.674876)
			(stroke
				(width 0.1)
				(type default)
			)
			(layer "F.Fab")
		)
		(fp_line
			(start -3.275076 1.674876)
			(end 3.275076 1.674876)
			(stroke
				(width 0.1)
				(type default)
			)
			(layer "F.Fab")
		)
		(pad "1" smd rect
			(at -2.350008 0 90)
			(size 2.921 3.5052)
			(layers "F.Cu" "F.Mask" "F.Paste")
			(net "P12V_SSD1")
		)
		(pad "2" smd rect
			(at 2.350008 0 90)
			(size 2.921 3.5052)
			(layers "F.Cu" "F.Mask" "F.Paste")
			(net "P12V_SSD1_R")
		)
	)
	(footprint ""
		(layer "F.Cu")
		(at 104.267762 -56.353456)
		(property "Reference" "C2867"
			(at 0 0 0)
			(layer "F.SilkS")
			(hide yes)
			(effects
				(font
					(size 1.27 1.27)
				)
			)
		)
		(property "Value" ""
			(at 0 0 0)
			(layer "F.Fab")
			(effects
				(font
					(size 1.27 1.27)
				)
			)
		)
		(duplicate_pad_numbers_are_jumpers no)
		(fp_line
			(start -0.7874 -0.4064)
			(end 0.7874 -0.4064)
			(stroke
				(width 0.1524)
				(type default)
			)
			(layer "F.SilkS")
		)
		(fp_line
			(start -0.7874 0.4064)
			(end -0.7874 -0.4064)
			(stroke
				(width 0.1524)
				(type default)
			)
			(layer "F.SilkS")
		)
		(fp_line
			(start 0.7874 -0.4064)
			(end 0.7874 0.4064)
			(stroke
				(width 0.1524)
				(type default)
			)
			(layer "F.SilkS")
		)
		(fp_line
			(start 0.7874 0.4064)
			(end -0.7874 0.4064)
			(stroke
				(width 0.1524)
				(type default)
			)
			(layer "F.SilkS")
		)
		(fp_line
			(start -0.67945 -0.305054)
			(end -0.12065 -0.305054)
			(stroke
				(width 0.1)
				(type default)
			)
			(layer "F.Fab")
		)
		(fp_line
			(start -0.67945 0.3048)
			(end -0.67945 -0.305054)
			(stroke
				(width 0.1)
				(type default)
			)
			(layer "F.Fab")
		)
		(fp_line
			(start -0.12065 -0.305054)
			(end -0.12065 -0.2794)
			(stroke
				(width 0.1)
				(type default)
			)
			(layer "F.Fab")
		)
		(fp_line
			(start -0.12065 -0.2794)
			(end 0.12065 -0.2794)
			(stroke
				(width 0.1)
				(type default)
			)
			(layer "F.Fab")
		)
		(fp_line
			(start -0.12065 0.2794)
			(end -0.12065 0.3048)
			(stroke
				(width 0.1)
				(type default)
			)
			(layer "F.Fab")
		)
		(fp_line
			(start -0.12065 0.3048)
			(end -0.67945 0.3048)
			(stroke
				(width 0.1)
				(type default)
			)
			(layer "F.Fab")
		)
		(fp_line
			(start 0.120396 0.2794)
			(end -0.12065 0.2794)
			(stroke
				(width 0.1)
				(type default)
			)
			(layer "F.Fab")
		)
		(fp_line
			(start 0.120396 0.3048)
			(end 0.120396 0.2794)
			(stroke
				(width 0.1)
				(type default)
			)
			(layer "F.Fab")
		)
		(fp_line
			(start 0.12065 -0.3048)
			(end 0.67945 -0.3048)
			(stroke
				(width 0.1)
				(type default)
			)
			(layer "F.Fab")
		)
		(fp_line
			(start 0.12065 -0.2794)
			(end 0.12065 -0.3048)
			(stroke
				(width 0.1)
				(type default)
			)
			(layer "F.Fab")
		)
		(fp_line
			(start 0.67945 -0.3048)
			(end 0.67945 0.3048)
			(stroke
				(width 0.1)
				(type default)
			)
			(layer "F.Fab")
		)
		(fp_line
			(start 0.67945 0.3048)
			(end 0.120396 0.3048)
			(stroke
				(width 0.1)
				(type default)
			)
			(layer "F.Fab")
		)
		(pad "1" smd circle
			(at -0.40005 0)
			(size 0 0)
			(layers "F.Cu" "F.Mask" "F.Paste")
			(net "SSD3_PWR_EN_R")
		)
		(pad "2" smd circle
			(at 0.40005 0)
			(size 0 0)
			(layers "F.Cu" "F.Mask" "F.Paste")
			(net "GND")
		)
	)
	(footprint ""
		(layer "F.Cu")
		(at 104.243632 -42.84091)
		(property "Reference" "R539"
			(at 0 0 0)
			(layer "F.SilkS")
			(hide yes)
			(effects
				(font
					(size 1.27 1.27)
				)
			)
		)
		(property "Value" ""
			(at 0 0 0)
			(layer "F.Fab")
			(effects
				(font
					(size 1.27 1.27)
				)
			)
		)
		(duplicate_pad_numbers_are_jumpers no)
		(fp_line
			(start -0.7874 -0.4064)
			(end 0.7874 -0.4064)
			(stroke
				(width 0.1524)
				(type default)
			)
			(layer "F.SilkS")
		)
		(fp_line
			(start -0.7874 0.4064)
			(end -0.7874 -0.4064)
			(stroke
				(width 0.1524)
				(type default)
			)
			(layer "F.SilkS")
		)
		(fp_line
			(start 0.7874 -0.4064)
			(end 0.7874 0.4064)
			(stroke
				(width 0.1524)
				(type default)
			)
			(layer "F.SilkS")
		)
		(fp_line
			(start 0.7874 0.4064)
			(end -0.7874 0.4064)
			(stroke
				(width 0.1524)
				(type default)
			)
			(layer "F.SilkS")
		)
		(fp_line
			(start -0.67945 -0.305054)
			(end -0.12065 -0.305054)
			(stroke
				(width 0.1)
				(type default)
			)
			(layer "F.Fab")
		)
		(fp_line
			(start -0.67945 0.3048)
			(end -0.67945 -0.305054)
			(stroke
				(width 0.1)
				(type default)
			)
			(layer "F.Fab")
		)
		(fp_line
			(start -0.12065 -0.305054)
			(end -0.12065 -0.2794)
			(stroke
				(width 0.1)
				(type default)
			)
			(layer "F.Fab")
		)
		(fp_line
			(start -0.12065 -0.2794)
			(end 0.12065 -0.2794)
			(stroke
				(width 0.1)
				(type default)
			)
			(layer "F.Fab")
		)
		(fp_line
			(start -0.12065 0.2794)
			(end -0.12065 0.3048)
			(stroke
				(width 0.1)
				(type default)
			)
			(layer "F.Fab")
		)
		(fp_line
			(start -0.12065 0.3048)
			(end -0.67945 0.3048)
			(stroke
				(width 0.1)
				(type default)
			)
			(layer "F.Fab")
		)
		(fp_line
			(start 0.120396 0.2794)
			(end -0.12065 0.2794)
			(stroke
				(width 0.1)
				(type default)
			)
			(layer "F.Fab")
		)
		(fp_line
			(start 0.120396 0.3048)
			(end 0.120396 0.2794)
			(stroke
				(width 0.1)
				(type default)
			)
			(layer "F.Fab")
		)
		(fp_line
			(start 0.12065 -0.3048)
			(end 0.67945 -0.3048)
			(stroke
				(width 0.1)
				(type default)
			)
			(layer "F.Fab")
		)
		(fp_line
			(start 0.12065 -0.2794)
			(end 0.12065 -0.3048)
			(stroke
				(width 0.1)
				(type default)
			)
			(layer "F.Fab")
		)
		(fp_line
			(start 0.67945 -0.3048)
			(end 0.67945 0.3048)
			(stroke
				(width 0.1)
				(type default)
			)
			(layer "F.Fab")
		)
		(fp_line
			(start 0.67945 0.3048)
			(end 0.120396 0.3048)
			(stroke
				(width 0.1)
				(type default)
			)
			(layer "F.Fab")
		)
		(pad "1" smd circle
			(at -0.40005 0)
			(size 0 0)
			(layers "F.Cu" "F.Mask" "F.Paste")
			(net "SSD3_ADC_A1")
		)
		(pad "2" smd circle
			(at 0.40005 0)
			(size 0 0)
			(layers "F.Cu" "F.Mask" "F.Paste")
			(net "P3V3_AUX")
		)
	)
)
